(kicad_pcb
	(version 20260206)
	(generator "pcbnew")
	(generator_version "10.0")
	(general
		(thickness 1.6)
		(legacy_teardrops no)
	)
	(paper "A4")
	(title_block
		(title "Wiwynn_Tioga_Pass_MB.brd")
		(comment 1 "Tioga Pass / footprint 3319 of 4770 (J6L2), pads 1-123 of 291")
	)
	(layers
		(0 "F.Cu" signal "TOP")
		(4 "In1.Cu" signal "L2GND")
		(6 "In2.Cu" signal "L3")
		(8 "In3.Cu" signal "L4GND")
		(10 "In4.Cu" signal "L5")
		(12 "In5.Cu" signal "L6GND")
		(14 "In6.Cu" signal "L7VCC")
		(16 "In7.Cu" signal "L8VCC")
		(18 "In8.Cu" signal "L9GND")
		(20 "In9.Cu" signal "L10")
		(22 "In10.Cu" signal "L11GND")
		(24 "In11.Cu" signal "L12")
		(26 "In12.Cu" signal "L13GND")
		(2 "B.Cu" signal "BOTTOM")
		(9 "F.Adhes" user "F.Adhesive")
		(11 "B.Adhes" user "B.Adhesive")
		(13 "F.Paste" user "Package Geometry/Pastemask Top")
		(15 "B.Paste" user "Package Geometry/Pastemask Bottom")
		(5 "F.SilkS" user "Ref Des/Silkscreen Top")
		(7 "B.SilkS" user "Ref Des/Silkscreen Bottom")
		(1 "F.Mask" user "Board Geometry/Soldermask Top")
		(3 "B.Mask" user "Board Geometry/Soldermask Bottom")
		(17 "Dwgs.User" user "User.Drawings")
		(19 "Cmts.User" user "User.Comments")
		(21 "Eco1.User" user "User.Eco1")
		(23 "Eco2.User" user "User.Eco2")
		(25 "Edge.Cuts" user "Board Geometry/Outline")
		(27 "Margin" user)
		(31 "F.CrtYd" user "Package Geometry/Place Bound Top")
		(29 "B.CrtYd" user "Package Geometry/Place Bound Bottom")
		(35 "F.Fab" user "Ref Des/Assembly Top")
		(33 "B.Fab" user "Ref Des/Assembly Bottom")
	)
	(footprint ""
		(layer "B.Cu")
		(at 194.700398 -142.477236 90)
		(property "Reference" "J6L2"
			(at 2.276348 38.21811 0)
			(unlocked yes)
			(layer "B.SilkS")
			(effects
				(font
					(size 0.7874 0.5842)
					(thickness 0.1524)
				)
				(justify left mirror)
			)
		)
		(property "Value" ""
			(at 0 0 90)
			(layer "B.Fab")
			(effects
				(font
					(size 1.27 1.27)
				)
				(justify mirror)
			)
		)
		(duplicate_pad_numbers_are_jumpers no)
		(pad "" thru_hole circle
			(at -2.29997 -5.649976 270)
			(size 2.8194 2.8194)
			(drill 2.4384)
			(layers "*.Cu" "*.Mask")
			(remove_unused_layers no)
			(clearance 0.127)
			(thermal_gap 0.127)
		)
		(pad "" thru_hole oval
			(at -2.29997 68.90004 270)
			(size 2.8194 1.5748)
			(drill oval 2.4384 1.1938)
			(layers "*.Cu" "*.Mask")
			(remove_unused_layers no)
			(clearance 0.127)
			(thermal_gap 0.127)
		)
		(pad "" thru_hole circle
			(at -2.29997 132.299964 270)
			(size 2.8194 2.8194)
			(drill 2.4384)
			(layers "*.Cu" "*.Mask")
			(remove_unused_layers no)
			(clearance 0.127)
			(thermal_gap 0.127)
		)
		(pad "1" smd rect
			(at 0 0 270)
			(size 1.8034 0.508)
			(layers "B.Cu" "B.Mask" "B.Paste")
			(net "P12V_NVDIMM_DEF")
		)
		(pad "2" smd rect
			(at 0 0.849884 270)
			(size 1.8034 0.508)
			(layers "B.Cu" "B.Mask" "B.Paste")
			(net "GND")
		)
		(pad "3" smd rect
			(at 0 1.700022 270)
			(size 1.8034 0.508)
			(layers "B.Cu" "B.Mask" "B.Paste")
			(net "M_E_DQ<4>")
		)
		(pad "4" smd rect
			(at 0 2.549906 270)
			(size 1.8034 0.508)
			(layers "B.Cu" "B.Mask" "B.Paste")
			(net "GND")
		)
		(pad "5" smd rect
			(at 0 3.400044 270)
			(size 1.8034 0.508)
			(layers "B.Cu" "B.Mask" "B.Paste")
			(net "M_E_DQ<0>")
		)
		(pad "6" smd rect
			(at 0 4.249928 270)
			(size 1.8034 0.508)
			(layers "B.Cu" "B.Mask" "B.Paste")
			(net "GND")
		)
		(pad "7" smd rect
			(at 0 5.100066 270)
			(size 1.8034 0.508)
			(layers "B.Cu" "B.Mask" "B.Paste")
			(net "M_E_DQS_DP<9>")
		)
		(pad "8" smd rect
			(at 0 5.94995 270)
			(size 1.8034 0.508)
			(layers "B.Cu" "B.Mask" "B.Paste")
			(net "M_E_DQS_DN<9>")
		)
		(pad "9" smd rect
			(at 0 6.800088 270)
			(size 1.8034 0.508)
			(layers "B.Cu" "B.Mask" "B.Paste")
			(net "GND")
		)
		(pad "10" smd rect
			(at 0 7.649972 270)
			(size 1.8034 0.508)
			(layers "B.Cu" "B.Mask" "B.Paste")
			(net "M_E_DQ<6>")
		)
		(pad "11" smd rect
			(at 0 8.50011 270)
			(size 1.8034 0.508)
			(layers "B.Cu" "B.Mask" "B.Paste")
			(net "GND")
		)
		(pad "12" smd rect
			(at 0 9.349994 270)
			(size 1.8034 0.508)
			(layers "B.Cu" "B.Mask" "B.Paste")
			(net "M_E_DQ<2>")
		)
		(pad "13" smd rect
			(at 0 10.199878 270)
			(size 1.8034 0.508)
			(layers "B.Cu" "B.Mask" "B.Paste")
			(net "GND")
		)
		(pad "14" smd rect
			(at 0 11.050016 270)
			(size 1.8034 0.508)
			(layers "B.Cu" "B.Mask" "B.Paste")
			(net "M_E_DQ<12>")
		)
		(pad "15" smd rect
			(at 0 11.8999 270)
			(size 1.8034 0.508)
			(layers "B.Cu" "B.Mask" "B.Paste")
			(net "GND")
		)
		(pad "16" smd rect
			(at 0 12.750038 270)
			(size 1.8034 0.508)
			(layers "B.Cu" "B.Mask" "B.Paste")
			(net "M_E_DQ<8>")
		)
		(pad "17" smd rect
			(at 0 13.599922 270)
			(size 1.8034 0.508)
			(layers "B.Cu" "B.Mask" "B.Paste")
			(net "GND")
		)
		(pad "18" smd rect
			(at 0 14.45006 270)
			(size 1.8034 0.508)
			(layers "B.Cu" "B.Mask" "B.Paste")
			(net "M_E_DQS_DP<10>")
		)
		(pad "19" smd rect
			(at 0 15.299944 270)
			(size 1.8034 0.508)
			(layers "B.Cu" "B.Mask" "B.Paste")
			(net "M_E_DQS_DN<10>")
		)
		(pad "20" smd rect
			(at 0 16.150082 270)
			(size 1.8034 0.508)
			(layers "B.Cu" "B.Mask" "B.Paste")
			(net "GND")
		)
		(pad "21" smd rect
			(at 0 16.999966 270)
			(size 1.8034 0.508)
			(layers "B.Cu" "B.Mask" "B.Paste")
			(net "M_E_DQ<14>")
		)
		(pad "22" smd rect
			(at 0 17.850104 270)
			(size 1.8034 0.508)
			(layers "B.Cu" "B.Mask" "B.Paste")
			(net "GND")
		)
		(pad "23" smd rect
			(at 0 18.699988 270)
			(size 1.8034 0.508)
			(layers "B.Cu" "B.Mask" "B.Paste")
			(net "M_E_DQ<10>")
		)
		(pad "24" smd rect
			(at 0 19.550126 270)
			(size 1.8034 0.508)
			(layers "B.Cu" "B.Mask" "B.Paste")
			(net "GND")
		)
		(pad "25" smd rect
			(at 0 20.40001 270)
			(size 1.8034 0.508)
			(layers "B.Cu" "B.Mask" "B.Paste")
			(net "M_E_DQ<20>")
		)
		(pad "26" smd rect
			(at 0 21.249894 270)
			(size 1.8034 0.508)
			(layers "B.Cu" "B.Mask" "B.Paste")
			(net "GND")
		)
		(pad "27" smd rect
			(at 0 22.100032 270)
			(size 1.8034 0.508)
			(layers "B.Cu" "B.Mask" "B.Paste")
			(net "M_E_DQ<16>")
		)
		(pad "28" smd rect
			(at 0 22.949916 270)
			(size 1.8034 0.508)
			(layers "B.Cu" "B.Mask" "B.Paste")
			(net "GND")
		)
		(pad "29" smd rect
			(at 0 23.800054 270)
			(size 1.8034 0.508)
			(layers "B.Cu" "B.Mask" "B.Paste")
			(net "M_E_DQS_DP<11>")
		)
		(pad "30" smd rect
			(at 0 24.649938 270)
			(size 1.8034 0.508)
			(layers "B.Cu" "B.Mask" "B.Paste")
			(net "M_E_DQS_DN<11>")
		)
		(pad "31" smd rect
			(at 0 25.500076 270)
			(size 1.8034 0.508)
			(layers "B.Cu" "B.Mask" "B.Paste")
			(net "GND")
		)
		(pad "32" smd rect
			(at 0 26.34996 270)
			(size 1.8034 0.508)
			(layers "B.Cu" "B.Mask" "B.Paste")
			(net "M_E_DQ<22>")
		)
		(pad "33" smd rect
			(at 0 27.200098 270)
			(size 1.8034 0.508)
			(layers "B.Cu" "B.Mask" "B.Paste")
			(net "GND")
		)
		(pad "34" smd rect
			(at 0 28.049982 270)
			(size 1.8034 0.508)
			(layers "B.Cu" "B.Mask" "B.Paste")
			(net "M_E_DQ<18>")
		)
		(pad "35" smd rect
			(at 0 28.90012 270)
			(size 1.8034 0.508)
			(layers "B.Cu" "B.Mask" "B.Paste")
			(net "GND")
		)
		(pad "36" smd rect
			(at 0 29.750004 270)
			(size 1.8034 0.508)
			(layers "B.Cu" "B.Mask" "B.Paste")
			(net "M_E_DQ<28>")
		)
		(pad "37" smd rect
			(at 0 30.599888 270)
			(size 1.8034 0.508)
			(layers "B.Cu" "B.Mask" "B.Paste")
			(net "GND")
		)
		(pad "38" smd rect
			(at 0 31.450026 270)
			(size 1.8034 0.508)
			(layers "B.Cu" "B.Mask" "B.Paste")
			(net "M_E_DQ<24>")
		)
		(pad "39" smd rect
			(at 0 32.29991 270)
			(size 1.8034 0.508)
			(layers "B.Cu" "B.Mask" "B.Paste")
			(net "GND")
		)
		(pad "40" smd rect
			(at 0 33.150048 270)
			(size 1.8034 0.508)
			(layers "B.Cu" "B.Mask" "B.Paste")
			(net "M_E_DQS_DP<12>")
		)
		(pad "41" smd rect
			(at 0 33.999932 270)
			(size 1.8034 0.508)
			(layers "B.Cu" "B.Mask" "B.Paste")
			(net "M_E_DQS_DN<12>")
		)
		(pad "42" smd rect
			(at 0 34.85007 270)
			(size 1.8034 0.508)
			(layers "B.Cu" "B.Mask" "B.Paste")
			(net "GND")
		)
		(pad "43" smd rect
			(at 0 35.699954 270)
			(size 1.8034 0.508)
			(layers "B.Cu" "B.Mask" "B.Paste")
			(net "M_E_DQ<30>")
		)
		(pad "44" smd rect
			(at 0 36.550092 270)
			(size 1.8034 0.508)
			(layers "B.Cu" "B.Mask" "B.Paste")
			(net "GND")
		)
		(pad "45" smd rect
			(at 0 37.399976 270)
			(size 1.8034 0.508)
			(layers "B.Cu" "B.Mask" "B.Paste")
			(net "M_E_DQ<26>")
		)
		(pad "46" smd rect
			(at 0 38.250114 270)
			(size 1.8034 0.508)
			(layers "B.Cu" "B.Mask" "B.Paste")
			(net "GND")
		)
		(pad "47" smd rect
			(at 0 39.099998 270)
			(size 1.8034 0.508)
			(layers "B.Cu" "B.Mask" "B.Paste")
			(net "M_E_ECC<4>")
		)
		(pad "48" smd rect
			(at 0 39.949882 270)
			(size 1.8034 0.508)
			(layers "B.Cu" "B.Mask" "B.Paste")
			(net "GND")
		)
		(pad "49" smd rect
			(at 0 40.80002 270)
			(size 1.8034 0.508)
			(layers "B.Cu" "B.Mask" "B.Paste")
			(net "M_E_ECC<0>")
		)
		(pad "50" smd rect
			(at 0 41.649904 270)
			(size 1.8034 0.508)
			(layers "B.Cu" "B.Mask" "B.Paste")
			(net "GND")
		)
		(pad "51" smd rect
			(at 0 42.500042 270)
			(size 1.8034 0.508)
			(layers "B.Cu" "B.Mask" "B.Paste")
			(net "M_E_DQS_DP<17>")
		)
		(pad "52" smd rect
			(at 0 43.349926 270)
			(size 1.8034 0.508)
			(layers "B.Cu" "B.Mask" "B.Paste")
			(net "M_E_DQS_DN<17>")
		)
		(pad "53" smd rect
			(at 0 44.200064 270)
			(size 1.8034 0.508)
			(layers "B.Cu" "B.Mask" "B.Paste")
			(net "GND")
		)
		(pad "54" smd rect
			(at 0 45.049948 270)
			(size 1.8034 0.508)
			(layers "B.Cu" "B.Mask" "B.Paste")
			(net "M_E_ECC<6>")
		)
		(pad "55" smd rect
			(at 0 45.900086 270)
			(size 1.8034 0.508)
			(layers "B.Cu" "B.Mask" "B.Paste")
			(net "GND")
		)
		(pad "56" smd rect
			(at 0 46.74997 270)
			(size 1.8034 0.508)
			(layers "B.Cu" "B.Mask" "B.Paste")
			(net "M_E_ECC<2>")
		)
		(pad "57" smd rect
			(at 0 47.600108 270)
			(size 1.8034 0.508)
			(layers "B.Cu" "B.Mask" "B.Paste")
			(net "GND")
		)
		(pad "58" smd rect
			(at 0 48.449992 270)
			(size 1.8034 0.508)
			(layers "B.Cu" "B.Mask" "B.Paste")
			(net "M_DEF_RST_N")
		)
		(pad "59" smd rect
			(at 0 49.299876 270)
			(size 1.8034 0.508)
			(layers "B.Cu" "B.Mask" "B.Paste")
			(net "PVDDQ_DEF")
		)
		(pad "60" smd rect
			(at 0 50.150014 270)
			(size 1.8034 0.508)
			(layers "B.Cu" "B.Mask" "B.Paste")
			(net "M_E_CKE<2>")
		)
		(pad "61" smd rect
			(at 0 50.999898 270)
			(size 1.8034 0.508)
			(layers "B.Cu" "B.Mask" "B.Paste")
			(net "PVDDQ_DEF")
		)
		(pad "62" smd rect
			(at 0 51.850036 270)
			(size 1.8034 0.508)
			(layers "B.Cu" "B.Mask" "B.Paste")
			(net "M_E_ACT_N")
		)
		(pad "63" smd rect
			(at 0 52.69992 270)
			(size 1.8034 0.508)
			(layers "B.Cu" "B.Mask" "B.Paste")
			(net "M_E_BG<0>")
		)
		(pad "64" smd rect
			(at 0 53.550058 270)
			(size 1.8034 0.508)
			(layers "B.Cu" "B.Mask" "B.Paste")
			(net "PVDDQ_DEF")
		)
		(pad "65" smd rect
			(at 0 54.399942 270)
			(size 1.8034 0.508)
			(layers "B.Cu" "B.Mask" "B.Paste")
			(net "M_E_MA<12>")
		)
		(pad "66" smd rect
			(at 0 55.25008 270)
			(size 1.8034 0.508)
			(layers "B.Cu" "B.Mask" "B.Paste")
			(net "M_E_MA<9>")
		)
		(pad "67" smd rect
			(at 0 56.099964 270)
			(size 1.8034 0.508)
			(layers "B.Cu" "B.Mask" "B.Paste")
			(net "PVDDQ_DEF")
		)
		(pad "68" smd rect
			(at 0 56.950102 270)
			(size 1.8034 0.508)
			(layers "B.Cu" "B.Mask" "B.Paste")
			(net "M_E_MA<8>")
		)
		(pad "69" smd rect
			(at 0 57.799986 270)
			(size 1.8034 0.508)
			(layers "B.Cu" "B.Mask" "B.Paste")
			(net "M_E_MA<6>")
		)
		(pad "70" smd rect
			(at 0 58.650124 270)
			(size 1.8034 0.508)
			(layers "B.Cu" "B.Mask" "B.Paste")
			(net "PVDDQ_DEF")
		)
		(pad "71" smd rect
			(at 0 59.500008 270)
			(size 1.8034 0.508)
			(layers "B.Cu" "B.Mask" "B.Paste")
			(net "M_E_MA<3>")
		)
		(pad "72" smd rect
			(at 0 60.349892 270)
			(size 1.8034 0.508)
			(layers "B.Cu" "B.Mask" "B.Paste")
			(net "M_E_MA<1>")
		)
		(pad "73" smd rect
			(at 0 61.20003 270)
			(size 1.8034 0.508)
			(layers "B.Cu" "B.Mask" "B.Paste")
			(net "PVDDQ_DEF")
		)
		(pad "74" smd rect
			(at 0 62.049914 270)
			(size 1.8034 0.508)
			(layers "B.Cu" "B.Mask" "B.Paste")
			(net "M_E_CLK_DP<2>")
		)
		(pad "75" smd rect
			(at 0 62.900052 270)
			(size 1.8034 0.508)
			(layers "B.Cu" "B.Mask" "B.Paste")
			(net "M_E_CLK_DN<2>")
		)
		(pad "76" smd rect
			(at 0 63.749936 270)
			(size 1.8034 0.508)
			(layers "B.Cu" "B.Mask" "B.Paste")
			(net "PVDDQ_DEF")
		)
		(pad "77" smd rect
			(at 0 64.600074 270)
			(size 1.8034 0.508)
			(layers "B.Cu" "B.Mask" "B.Paste")
			(net "PVTT_DEF")
		)
		(pad "78" smd rect
			(at 0 70.550024 270)
			(size 1.8034 0.508)
			(layers "B.Cu" "B.Mask" "B.Paste")
			(net "FM_DIMM_EVENT_COD_N")
		)
		(pad "79" smd rect
			(at 0 71.399908 270)
			(size 1.8034 0.508)
			(layers "B.Cu" "B.Mask" "B.Paste")
			(net "M_E_MA<0>")
		)
		(pad "80" smd rect
			(at 0 72.250046 270)
			(size 1.8034 0.508)
			(layers "B.Cu" "B.Mask" "B.Paste")
			(net "PVDDQ_DEF")
		)
		(pad "81" smd rect
			(at 0 73.09993 270)
			(size 1.8034 0.508)
			(layers "B.Cu" "B.Mask" "B.Paste")
			(net "M_E_BA<0>")
		)
		(pad "82" smd rect
			(at 0 73.950068 270)
			(size 1.8034 0.508)
			(layers "B.Cu" "B.Mask" "B.Paste")
			(net "M_E_MA<16>")
		)
		(pad "83" smd rect
			(at 0 74.799952 270)
			(size 1.8034 0.508)
			(layers "B.Cu" "B.Mask" "B.Paste")
			(net "PVDDQ_DEF")
		)
		(pad "84" smd rect
			(at 0 75.65009 270)
			(size 1.8034 0.508)
			(layers "B.Cu" "B.Mask" "B.Paste")
			(net "M_E_CS_N<4>")
		)
		(pad "85" smd rect
			(at 0 76.499974 270)
			(size 1.8034 0.508)
			(layers "B.Cu" "B.Mask" "B.Paste")
			(net "PVDDQ_DEF")
		)
		(pad "86" smd rect
			(at 0 77.350112 270)
			(size 1.8034 0.508)
			(layers "B.Cu" "B.Mask" "B.Paste")
			(net "M_E_MA<15>")
		)
		(pad "87" smd rect
			(at 0 78.199996 270)
			(size 1.8034 0.508)
			(layers "B.Cu" "B.Mask" "B.Paste")
			(net "M_E_ODT<2>")
		)
		(pad "88" smd rect
			(at 0 79.04988 270)
			(size 1.8034 0.508)
			(layers "B.Cu" "B.Mask" "B.Paste")
			(net "PVDDQ_DEF")
		)
		(pad "89" smd rect
			(at 0 79.900018 270)
			(size 1.8034 0.508)
			(layers "B.Cu" "B.Mask" "B.Paste")
			(net "M_E_CS_N<5>")
		)
		(pad "90" smd rect
			(at 0 80.749902 270)
			(size 1.8034 0.508)
			(layers "B.Cu" "B.Mask" "B.Paste")
			(net "PVDDQ_DEF")
		)
		(pad "91" smd rect
			(at 0 81.60004 270)
			(size 1.8034 0.508)
			(layers "B.Cu" "B.Mask" "B.Paste")
			(net "M_E_ODT<3>")
		)
		(pad "92" smd rect
			(at 0 82.449924 270)
			(size 1.8034 0.508)
			(layers "B.Cu" "B.Mask" "B.Paste")
			(net "PVDDQ_DEF")
		)
		(pad "93" smd rect
			(at 0 83.300062 270)
			(size 1.8034 0.508)
			(layers "B.Cu" "B.Mask" "B.Paste")
			(net "M_E_CS_N<6>")
		)
		(pad "94" smd rect
			(at 0 84.149946 270)
			(size 1.8034 0.508)
			(layers "B.Cu" "B.Mask" "B.Paste")
			(net "GND")
		)
		(pad "95" smd rect
			(at 0 85.000084 270)
			(size 1.8034 0.508)
			(layers "B.Cu" "B.Mask" "B.Paste")
			(net "M_E_DQ<36>")
		)
		(pad "96" smd rect
			(at 0 85.849968 270)
			(size 1.8034 0.508)
			(layers "B.Cu" "B.Mask" "B.Paste")
			(net "GND")
		)
		(pad "97" smd rect
			(at 0 86.700106 270)
			(size 1.8034 0.508)
			(layers "B.Cu" "B.Mask" "B.Paste")
			(net "M_E_DQ<32>")
		)
		(pad "98" smd rect
			(at 0 87.54999 270)
			(size 1.8034 0.508)
			(layers "B.Cu" "B.Mask" "B.Paste")
			(net "GND")
		)
		(pad "99" smd rect
			(at 0 88.399874 270)
			(size 1.8034 0.508)
			(layers "B.Cu" "B.Mask" "B.Paste")
			(net "M_E_DQS_DP<13>")
		)
		(pad "100" smd rect
			(at 0 89.250012 270)
			(size 1.8034 0.508)
			(layers "B.Cu" "B.Mask" "B.Paste")
			(net "M_E_DQS_DN<13>")
		)
		(pad "101" smd rect
			(at 0 90.099896 270)
			(size 1.8034 0.508)
			(layers "B.Cu" "B.Mask" "B.Paste")
			(net "GND")
		)
		(pad "102" smd rect
			(at 0 90.950034 270)
			(size 1.8034 0.508)
			(layers "B.Cu" "B.Mask" "B.Paste")
			(net "M_E_DQ<38>")
		)
		(pad "103" smd rect
			(at 0 91.799918 270)
			(size 1.8034 0.508)
			(layers "B.Cu" "B.Mask" "B.Paste")
			(net "GND")
		)
		(pad "104" smd rect
			(at 0 92.650056 270)
			(size 1.8034 0.508)
			(layers "B.Cu" "B.Mask" "B.Paste")
			(net "M_E_DQ<34>")
		)
		(pad "105" smd rect
			(at 0 93.49994 270)
			(size 1.8034 0.508)
			(layers "B.Cu" "B.Mask" "B.Paste")
			(net "GND")
		)
		(pad "106" smd rect
			(at 0 94.350078 270)
			(size 1.8034 0.508)
			(layers "B.Cu" "B.Mask" "B.Paste")
			(net "M_E_DQ<44>")
		)
		(pad "107" smd rect
			(at 0 95.199962 270)
			(size 1.8034 0.508)
			(layers "B.Cu" "B.Mask" "B.Paste")
			(net "GND")
		)
		(pad "108" smd rect
			(at 0 96.0501 270)
			(size 1.8034 0.508)
			(layers "B.Cu" "B.Mask" "B.Paste")
			(net "M_E_DQ<40>")
		)
		(pad "109" smd rect
			(at 0 96.899984 270)
			(size 1.8034 0.508)
			(layers "B.Cu" "B.Mask" "B.Paste")
			(net "GND")
		)
		(pad "110" smd rect
			(at 0 97.750122 270)
			(size 1.8034 0.508)
			(layers "B.Cu" "B.Mask" "B.Paste")
			(net "M_E_DQS_DP<14>")
		)
		(pad "111" smd rect
			(at 0 98.600006 270)
			(size 1.8034 0.508)
			(layers "B.Cu" "B.Mask" "B.Paste")
			(net "M_E_DQS_DN<14>")
		)
		(pad "112" smd rect
			(at 0 99.44989 270)
			(size 1.8034 0.508)
			(layers "B.Cu" "B.Mask" "B.Paste")
			(net "GND")
		)
		(pad "113" smd rect
			(at 0 100.300028 270)
			(size 1.8034 0.508)
			(layers "B.Cu" "B.Mask" "B.Paste")
			(net "M_E_DQ<46>")
		)
		(pad "114" smd rect
			(at 0 101.149912 270)
			(size 1.8034 0.508)
			(layers "B.Cu" "B.Mask" "B.Paste")
			(net "GND")
		)
		(pad "115" smd rect
			(at 0 102.00005 270)
			(size 1.8034 0.508)
			(layers "B.Cu" "B.Mask" "B.Paste")
			(net "M_E_DQ<42>")
		)
		(pad "116" smd rect
			(at 0 102.849934 270)
			(size 1.8034 0.508)
			(layers "B.Cu" "B.Mask" "B.Paste")
			(net "GND")
		)
		(pad "117" smd rect
			(at 0 103.700072 270)
			(size 1.8034 0.508)
			(layers "B.Cu" "B.Mask" "B.Paste")
			(net "M_E_DQ<52>")
		)
		(pad "118" smd rect
			(at 0 104.549956 270)
			(size 1.8034 0.508)
			(layers "B.Cu" "B.Mask" "B.Paste")
			(net "GND")
		)
		(pad "119" smd rect
			(at 0 105.400094 270)
			(size 1.8034 0.508)
			(layers "B.Cu" "B.Mask" "B.Paste")
			(net "M_E_DQ<48>")
		)
		(pad "120" smd rect
			(at 0 106.249978 270)
			(size 1.8034 0.508)
			(layers "B.Cu" "B.Mask" "B.Paste")
			(net "GND")
		)
	)
)
